(kicad_pcb
	(version 20260206)
	(generator "pcbnew")
	(generator_version "10.0")
	(general
		(thickness 1.6)
		(legacy_teardrops no)
	)
	(paper "A4")
	(title_block
		(title "Bryce Canyon_IOM_IOC_16318-2_OCP.brd")
		(comment 1 "Bryce Canyon / footprints 1041-1047 of 1605")
	)
	(layers
		(0 "F.Cu" signal "TOP")
		(4 "In1.Cu" signal "L2GND")
		(6 "In2.Cu" signal "L3")
		(8 "In3.Cu" signal "L4VCC")
		(10 "In4.Cu" signal "L5VCC")
		(12 "In5.Cu" signal "L6")
		(14 "In6.Cu" signal "L7GND")
		(2 "B.Cu" signal "BOTTOM")
		(9 "F.Adhes" user "F.Adhesive")
		(11 "B.Adhes" user "B.Adhesive")
		(13 "F.Paste" user "Package Geometry/Pastemask Top")
		(15 "B.Paste" user "Package Geometry/Pastemask Bottom")
		(5 "F.SilkS" user "Ref Des/Silkscreen Top")
		(7 "B.SilkS" user "Ref Des/Silkscreen Bottom")
		(1 "F.Mask" user "Board Geometry/Soldermask Top")
		(3 "B.Mask" user "Board Geometry/Soldermask Bottom")
		(17 "Dwgs.User" user "User.Drawings")
		(19 "Cmts.User" user "User.Comments")
		(21 "Eco1.User" user "User.Eco1")
		(23 "Eco2.User" user "User.Eco2")
		(25 "Edge.Cuts" user "Board Geometry/Outline")
		(27 "Margin" user)
		(31 "F.CrtYd" user "Package Geometry/Place Bound Top")
		(29 "B.CrtYd" user "Package Geometry/Place Bound Bottom")
		(35 "F.Fab" user "Ref Des/Assembly Top")
		(33 "B.Fab" user "Ref Des/Assembly Bottom")
	)
	(footprint ""
		(layer "B.Cu")
		(at 50.772568 -127.335788 180)
		(property "Reference" "R294"
			(at 0 0 0)
			(layer "B.SilkS")
			(hide yes)
			(effects
				(font
					(size 1.27 1.27)
				)
				(justify mirror)
			)
		)
		(property "Value" "0R2J-2-GP"
			(at -0.064008 -3.993896 180)
			(unlocked yes)
			(layer "B.Fab")
			(hide yes)
			(effects
				(font
					(size 1.016 1.016)
					(thickness 0.1524)
				)
				(justify mirror)
			)
		)
		(property "Device Type" "R402H16"
			(at -0.064008 -5.517896 180)
			(unlocked yes)
			(layer "B.Fab")
			(hide yes)
			(effects
				(font
					(size 1.016 1.016)
					(thickness 0.1524)
				)
				(justify mirror)
			)
		)
		(duplicate_pad_numbers_are_jumpers no)
		(fp_line
			(start 0.508 -0.9398)
			(end 0.508 0.9398)
			(stroke
				(width 0.1524)
				(type default)
			)
			(layer "B.SilkS")
		)
		(fp_line
			(start -0.508 -0.9398)
			(end 0.508 -0.9398)
			(stroke
				(width 0.1524)
				(type default)
			)
			(layer "B.SilkS")
		)
		(fp_rect
			(start 0.508 0.9398)
			(end -0.508 -0.9398)
			(stroke
				(width 0)
				(type default)
			)
			(fill no)
			(layer "B.CrtYd")
		)
		(fp_rect
			(start 0.508 0.9398)
			(end -0.508 -0.9398)
			(stroke
				(width 0)
				(type default)
			)
			(fill no)
			(layer "B.Fab")
		)
		(pad "1" smd custom
			(at 0 -0.4445)
			(size 0.1397 0.1397)
			(layers "B.Cu" "B.Mask" "B.Paste")
			(net "P12V_A_PGOOD")
			(options
				(clearance outline)
				(anchor circle)
			)
			(primitives
				(gr_poly
					(pts
						(arc
							(start -0.1778 0.2794)
							(mid -0.249642 0.249642)
							(end -0.2794 0.1778)
						)
						(arc
							(start -0.2794 -0.1778)
							(mid -0.249642 -0.249642)
							(end -0.1778 -0.2794)
						)
						(arc
							(start 0.1778 -0.2794)
							(mid 0.249642 -0.249642)
							(end 0.2794 -0.1778)
						)
						(arc
							(start 0.2794 0.1778)
							(mid 0.249642 0.249642)
							(end 0.1778 0.2794)
						)
					)
					(width 0)
					(fill yes)
				)
			)
		)
		(pad "2" smd custom
			(at 0 0.4445)
			(size 0.1397 0.1397)
			(layers "B.Cu" "B.Mask" "B.Paste")
			(net "P12V_A_PGOOD_R")
			(options
				(clearance outline)
				(anchor circle)
			)
			(primitives
				(gr_poly
					(pts
						(arc
							(start -0.1778 0.2794)
							(mid -0.249642 0.249642)
							(end -0.2794 0.1778)
						)
						(arc
							(start -0.2794 -0.1778)
							(mid -0.249642 -0.249642)
							(end -0.1778 -0.2794)
						)
						(arc
							(start 0.1778 -0.2794)
							(mid 0.249642 -0.249642)
							(end 0.2794 -0.1778)
						)
						(arc
							(start 0.2794 0.1778)
							(mid 0.249642 0.249642)
							(end 0.1778 0.2794)
						)
					)
					(width 0)
					(fill yes)
				)
			)
		)
	)
	(footprint ""
		(layer "B.Cu")
		(at 165.324536 -38.416738)
		(property "Reference" "C498"
			(at 0 0 0)
			(layer "B.SilkS")
			(hide yes)
			(effects
				(font
					(size 1.27 1.27)
				)
				(justify mirror)
			)
		)
		(property "Value" "SCD01U16V1KX-GP"
			(at 2.8321 -1.7399 0)
			(unlocked yes)
			(layer "B.Fab")
			(hide yes)
			(effects
				(font
					(size 1.016 1.016)
					(thickness 0.1524)
				)
				(justify mirror)
			)
		)
		(property "Device Type" "C0201H13"
			(at 2.8321 -3.2639 0)
			(unlocked yes)
			(layer "B.Fab")
			(hide yes)
			(effects
				(font
					(size 1.016 1.016)
					(thickness 0.1524)
				)
				(justify mirror)
			)
		)
		(duplicate_pad_numbers_are_jumpers no)
		(fp_rect
			(start 0.2794 0.6477)
			(end -0.2794 -0.6477)
			(stroke
				(width 0)
				(type default)
			)
			(fill no)
			(layer "B.CrtYd")
		)
		(fp_rect
			(start 0.2794 0.6477)
			(end -0.2794 -0.6477)
			(stroke
				(width 0)
				(type default)
			)
			(fill no)
			(layer "B.Fab")
		)
		(pad "1" smd custom
			(at 0 -0.2794 180)
			(size 0.0762 0.0762)
			(layers "B.Cu" "B.Mask" "B.Paste")
			(net "PHY_CON_B_TO_IOC_3_DP")
			(options
				(clearance outline)
				(anchor circle)
			)
			(primitives
				(gr_poly
					(pts
						(arc
							(start 0.1524 0.127)
							(mid 0.137521 0.162921)
							(end 0.1016 0.1778)
						)
						(arc
							(start -0.1016 0.1778)
							(mid -0.137521 0.162921)
							(end -0.1524 0.127)
						)
						(arc
							(start -0.1524 -0.127)
							(mid -0.137521 -0.162921)
							(end -0.1016 -0.1778)
						)
						(arc
							(start 0.1016 -0.1778)
							(mid 0.137521 -0.162921)
							(end 0.1524 -0.127)
						)
					)
					(width 0)
					(fill yes)
				)
			)
		)
		(pad "2" smd custom
			(at 0 0.2794 180)
			(size 0.0762 0.0762)
			(layers "B.Cu" "B.Mask" "B.Paste")
			(net "PHY_CON_B_TO_IOC_3_DP_C")
			(options
				(clearance outline)
				(anchor circle)
			)
			(primitives
				(gr_poly
					(pts
						(arc
							(start 0.1524 0.127)
							(mid 0.137521 0.162921)
							(end 0.1016 0.1778)
						)
						(arc
							(start -0.1016 0.1778)
							(mid -0.137521 0.162921)
							(end -0.1524 0.127)
						)
						(arc
							(start -0.1524 -0.127)
							(mid -0.137521 -0.162921)
							(end -0.1016 -0.1778)
						)
						(arc
							(start 0.1016 -0.1778)
							(mid 0.137521 -0.162921)
							(end 0.1524 -0.127)
						)
					)
					(width 0)
					(fill yes)
				)
			)
		)
	)
	(footprint ""
		(layer "B.Cu")
		(at 97.94748 -180.0098 90)
		(property "Reference" "U16"
			(at 0 0 90)
			(layer "B.SilkS")
			(hide yes)
			(effects
				(font
					(size 1.27 1.27)
				)
				(justify mirror)
			)
		)
		(property "Value" "NX3L1G66GW-GP"
			(at 2.3368 -8.6868 90)
			(unlocked yes)
			(layer "B.Fab")
			(hide yes)
			(effects
				(font
					(size 1.016 1.016)
					(thickness 0.1524)
				)
				(justify mirror)
			)
		)
		(property "Device Type" "SC70-5H44"
			(at 2.3114 -10.414 90)
			(unlocked yes)
			(layer "B.Fab")
			(hide yes)
			(effects
				(font
					(size 1.016 1.016)
					(thickness 0.1524)
				)
				(justify mirror)
			)
		)
		(duplicate_pad_numbers_are_jumpers no)
		(fp_line
			(start -0.6604 -1.8034)
			(end -1.3843 -1.8034)
			(stroke
				(width 0.3302)
				(type default)
			)
			(layer "B.SilkS")
		)
		(fp_line
			(start -1.3843 -1.8034)
			(end -1.3843 -1.1176)
			(stroke
				(width 0.3302)
				(type default)
			)
			(layer "B.SilkS")
		)
		(fp_line
			(start 1.27 -1.7018)
			(end -1.27 -1.7018)
			(stroke
				(width 0.1524)
				(type default)
			)
			(layer "B.SilkS")
		)
		(fp_line
			(start -1.27 -1.7018)
			(end -1.27 1.7018)
			(stroke
				(width 0.1524)
				(type default)
			)
			(layer "B.SilkS")
		)
		(fp_line
			(start 1.27 1.7018)
			(end 1.27 -1.7018)
			(stroke
				(width 0.1524)
				(type default)
			)
			(layer "B.SilkS")
		)
		(fp_line
			(start -1.27 1.7018)
			(end 1.27 1.7018)
			(stroke
				(width 0.1524)
				(type default)
			)
			(layer "B.SilkS")
		)
		(fp_rect
			(start 1.524 1.9558)
			(end -1.524 -1.9558)
			(stroke
				(width 0)
				(type default)
			)
			(fill no)
			(layer "B.CrtYd")
		)
		(fp_poly
			(pts
				(xy 1.524 -1.9558) (xy -1.524 -1.9558) (xy -1.524 1.9558) (xy 1.524 1.9558)
			)
			(stroke
				(width 0)
				(type default)
			)
			(fill no)
			(layer "B.Fab")
		)
		(pad "1" smd rect
			(at -0.65024 -0.8255 270)
			(size 0.4064 1.2192)
			(layers "B.Cu" "B.Mask" "B.Paste")
			(net "I2C_BMC_COMP_ALERT_N_R")
		)
		(pad "2" smd rect
			(at 0 -0.8255 270)
			(size 0.4064 1.2192)
			(layers "B.Cu" "B.Mask" "B.Paste")
			(net "I2C_COMP_ALERT_N")
		)
		(pad "3" smd rect
			(at 0.65024 -0.8255 270)
			(size 0.4064 1.2192)
			(layers "B.Cu" "B.Mask" "B.Paste")
			(net "GND")
		)
		(pad "4" smd rect
			(at 0.65024 0.8255 270)
			(size 0.4064 1.2192)
			(layers "B.Cu" "B.Mask" "B.Paste")
			(net "COMP_PWR_EN")
		)
		(pad "5" smd rect
			(at -0.65024 0.8255 270)
			(size 0.4064 1.2192)
			(layers "B.Cu" "B.Mask" "B.Paste")
			(net "P3V3_STBY")
		)
	)
	(footprint ""
		(layer "B.Cu")
		(at 44.141898 -149.135338 90)
		(property "Reference" "R143"
			(at 0 0 90)
			(layer "B.SilkS")
			(hide yes)
			(effects
				(font
					(size 1.27 1.27)
				)
				(justify mirror)
			)
		)
		(property "Value" "1KR2D-1-GP"
			(at -0.064008 -3.993896 90)
			(unlocked yes)
			(layer "B.Fab")
			(hide yes)
			(effects
				(font
					(size 1.016 1.016)
					(thickness 0.1524)
				)
				(justify mirror)
			)
		)
		(property "Device Type" "R402H16"
			(at -0.064008 -5.517896 90)
			(unlocked yes)
			(layer "B.Fab")
			(hide yes)
			(effects
				(font
					(size 1.016 1.016)
					(thickness 0.1524)
				)
				(justify mirror)
			)
		)
		(duplicate_pad_numbers_are_jumpers no)
		(fp_line
			(start 0.508 -0.9398)
			(end 0.508 0.9398)
			(stroke
				(width 0.1524)
				(type default)
			)
			(layer "B.SilkS")
		)
		(fp_line
			(start -0.508 -0.9398)
			(end 0.508 -0.9398)
			(stroke
				(width 0.1524)
				(type default)
			)
			(layer "B.SilkS")
		)
		(fp_rect
			(start 0.508 0.9398)
			(end -0.508 -0.9398)
			(stroke
				(width 0)
				(type default)
			)
			(fill no)
			(layer "B.CrtYd")
		)
		(fp_rect
			(start 0.508 0.9398)
			(end -0.508 -0.9398)
			(stroke
				(width 0)
				(type default)
			)
			(fill no)
			(layer "B.Fab")
		)
		(pad "1" smd custom
			(at 0 -0.4445 270)
			(size 0.1397 0.1397)
			(layers "B.Cu" "B.Mask" "B.Paste")
			(net "DDR_VREF")
			(options
				(clearance outline)
				(anchor circle)
			)
			(primitives
				(gr_poly
					(pts
						(arc
							(start -0.1778 0.2794)
							(mid -0.249642 0.249642)
							(end -0.2794 0.1778)
						)
						(arc
							(start -0.2794 -0.1778)
							(mid -0.249642 -0.249642)
							(end -0.1778 -0.2794)
						)
						(arc
							(start 0.1778 -0.2794)
							(mid 0.249642 -0.249642)
							(end 0.2794 -0.1778)
						)
						(arc
							(start 0.2794 0.1778)
							(mid 0.249642 0.249642)
							(end 0.1778 0.2794)
						)
					)
					(width 0)
					(fill yes)
				)
			)
		)
		(pad "2" smd custom
			(at 0 0.4445 270)
			(size 0.1397 0.1397)
			(layers "B.Cu" "B.Mask" "B.Paste")
			(net "GND")
			(options
				(clearance outline)
				(anchor circle)
			)
			(primitives
				(gr_poly
					(pts
						(arc
							(start -0.1778 0.2794)
							(mid -0.249642 0.249642)
							(end -0.2794 0.1778)
						)
						(arc
							(start -0.2794 -0.1778)
							(mid -0.249642 -0.249642)
							(end -0.1778 -0.2794)
						)
						(arc
							(start 0.1778 -0.2794)
							(mid 0.249642 -0.249642)
							(end 0.2794 -0.1778)
						)
						(arc
							(start 0.2794 0.1778)
							(mid 0.249642 0.249642)
							(end 0.1778 0.2794)
						)
					)
					(width 0)
					(fill yes)
				)
			)
		)
	)
	(footprint ""
		(layer "B.Cu")
		(at 62.2808 -175.2854 180)
		(property "Reference" "C33"
			(at 0 0 0)
			(layer "B.SilkS")
			(hide yes)
			(effects
				(font
					(size 1.27 1.27)
				)
				(justify mirror)
			)
		)
		(property "Value" "SCD1U16V2KX-3GP"
			(at -1.1811 -2.7051 180)
			(unlocked yes)
			(layer "B.Fab")
			(hide yes)
			(effects
				(font
					(size 1.016 1.016)
					(thickness 0.1524)
				)
				(justify mirror)
			)
		)
		(property "Device Type" "C402H22"
			(at -1.1811 -4.2291 180)
			(unlocked yes)
			(layer "B.Fab")
			(hide yes)
			(effects
				(font
					(size 1.016 1.016)
					(thickness 0.1524)
				)
				(justify mirror)
			)
		)
		(duplicate_pad_numbers_are_jumpers no)
		(fp_rect
			(start 0.4318 0.9525)
			(end -0.4318 -0.9525)
			(stroke
				(width 0)
				(type default)
			)
			(fill no)
			(layer "B.CrtYd")
		)
		(fp_rect
			(start 0.4318 0.9525)
			(end -0.4318 -0.9525)
			(stroke
				(width 0)
				(type default)
			)
			(fill no)
			(layer "B.Fab")
		)
		(pad "1" smd custom
			(at 0 -0.4445)
			(size 0.1524 0.1524)
			(layers "B.Cu" "B.Mask" "B.Paste")
			(net "P3V3_STBY")
			(options
				(clearance outline)
				(anchor circle)
			)
			(primitives
				(gr_poly
					(pts
						(arc
							(start 0.3048 0.2032)
							(mid 0.275042 0.275042)
							(end 0.2032 0.3048)
						)
						(arc
							(start -0.2032 0.3048)
							(mid -0.275042 0.275042)
							(end -0.3048 0.2032)
						)
						(arc
							(start -0.3048 -0.2032)
							(mid -0.275042 -0.275042)
							(end -0.2032 -0.3048)
						)
						(arc
							(start 0.2032 -0.3048)
							(mid 0.275042 -0.275042)
							(end 0.3048 -0.2032)
						)
					)
					(width 0)
					(fill yes)
				)
			)
		)
		(pad "2" smd custom
			(at 0 0.4445)
			(size 0.1524 0.1524)
			(layers "B.Cu" "B.Mask" "B.Paste")
			(net "GND")
			(options
				(clearance outline)
				(anchor circle)
			)
			(primitives
				(gr_poly
					(pts
						(arc
							(start 0.3048 0.2032)
							(mid 0.275042 0.275042)
							(end 0.2032 0.3048)
						)
						(arc
							(start -0.2032 0.3048)
							(mid -0.275042 0.275042)
							(end -0.3048 0.2032)
						)
						(arc
							(start -0.3048 -0.2032)
							(mid -0.275042 -0.275042)
							(end -0.2032 -0.3048)
						)
						(arc
							(start 0.2032 -0.3048)
							(mid 0.275042 -0.275042)
							(end 0.3048 -0.2032)
						)
					)
					(width 0)
					(fill yes)
				)
			)
		)
	)
	(footprint ""
		(layer "B.Cu")
		(at 38.0238 -182.6768 180)
		(property "Reference" "R484"
			(at 0 0 0)
			(layer "B.SilkS")
			(hide yes)
			(effects
				(font
					(size 1.27 1.27)
				)
				(justify mirror)
			)
		)
		(property "Value" "3D01R5F-GP"
			(at 0 -8.9535 180)
			(unlocked yes)
			(layer "B.Fab")
			(hide yes)
			(effects
				(font
					(size 1.27 1.016)
					(thickness 0.1524)
				)
				(justify mirror)
			)
		)
		(property "Device Type" "R805H24"
			(at 0 -10.6299 180)
			(unlocked yes)
			(layer "B.Fab")
			(hide yes)
			(effects
				(font
					(size 1.27 1.016)
					(thickness 0.1524)
				)
				(justify mirror)
			)
		)
		(duplicate_pad_numbers_are_jumpers no)
		(fp_line
			(start 0.889 1.7018)
			(end -0.889 1.7018)
			(stroke
				(width 0.1524)
				(type default)
			)
			(layer "B.SilkS")
		)
		(fp_line
			(start 0.889 0.0762)
			(end 0.889 1.7018)
			(stroke
				(width 0.1524)
				(type default)
			)
			(layer "B.SilkS")
		)
		(fp_line
			(start 0.889 -1.7018)
			(end 0.889 0.2794)
			(stroke
				(width 0.1524)
				(type default)
			)
			(layer "B.SilkS")
		)
		(fp_line
			(start -0.889 1.7018)
			(end -0.889 -0.508)
			(stroke
				(width 0.1524)
				(type default)
			)
			(layer "B.SilkS")
		)
		(fp_line
			(start -0.889 -1.7018)
			(end 0.889 -1.7018)
			(stroke
				(width 0.1524)
				(type default)
			)
			(layer "B.SilkS")
		)
		(fp_line
			(start -0.889 -1.7018)
			(end -0.889 -0.381)
			(stroke
				(width 0.1524)
				(type default)
			)
			(layer "B.SilkS")
		)
		(fp_poly
			(pts
				(xy -0.9652 -1.778) (xy -0.9652 1.778) (xy 0.9652 1.778) (xy 0.9652 -1.778)
			)
			(stroke
				(width 0)
				(type default)
			)
			(fill no)
			(layer "B.CrtYd")
		)
		(fp_rect
			(start 0.9652 1.778)
			(end -0.9652 -1.778)
			(stroke
				(width 0)
				(type default)
			)
			(fill no)
			(layer "B.Fab")
		)
		(pad "1" smd rect
			(at 0 -0.9652)
			(size 1.397 1.143)
			(layers "B.Cu" "B.Mask" "B.Paste")
			(net "P3V3_VBST")
		)
		(pad "2" smd rect
			(at 0 0.9652)
			(size 1.397 1.143)
			(layers "B.Cu" "B.Mask" "B.Paste")
			(net "P3V3_VBST_RC")
		)
	)
	(footprint ""
		(layer "B.Cu")
		(at 192.8876 -51.8922 -90)
		(property "Reference" "C333"
			(at 0 0 90)
			(layer "B.SilkS")
			(hide yes)
			(effects
				(font
					(size 1.27 1.27)
				)
				(justify mirror)
			)
		)
		(property "Value" "SCD1U6D3V1KX-GP"
			(at 2.8321 -1.7399 270)
			(unlocked yes)
			(layer "B.Fab")
			(hide yes)
			(effects
				(font
					(size 1.016 1.016)
					(thickness 0.1524)
				)
				(justify mirror)
			)
		)
		(property "Device Type" "C0201H13"
			(at 2.8321 -3.2639 270)
			(unlocked yes)
			(layer "B.Fab")
			(hide yes)
			(effects
				(font
					(size 1.016 1.016)
					(thickness 0.1524)
				)
				(justify mirror)
			)
		)
		(duplicate_pad_numbers_are_jumpers no)
		(fp_rect
			(start 0.2794 0.6477)
			(end -0.2794 -0.6477)
			(stroke
				(width 0)
				(type default)
			)
			(fill no)
			(layer "B.CrtYd")
		)
		(fp_rect
			(start 0.2794 0.6477)
			(end -0.2794 -0.6477)
			(stroke
				(width 0)
				(type default)
			)
			(fill no)
			(layer "B.Fab")
		)
		(pad "1" smd custom
			(at 0 -0.2794 90)
			(size 0.0762 0.0762)
			(layers "B.Cu" "B.Mask" "B.Paste")
			(net "HM40ADC_VDDA")
			(options
				(clearance outline)
				(anchor circle)
			)
			(primitives
				(gr_poly
					(pts
						(arc
							(start 0.1524 0.127)
							(mid 0.137521 0.162921)
							(end 0.1016 0.1778)
						)
						(arc
							(start -0.1016 0.1778)
							(mid -0.137521 0.162921)
							(end -0.1524 0.127)
						)
						(arc
							(start -0.1524 -0.127)
							(mid -0.137521 -0.162921)
							(end -0.1016 -0.1778)
						)
						(arc
							(start 0.1016 -0.1778)
							(mid 0.137521 -0.162921)
							(end 0.1524 -0.127)
						)
					)
					(width 0)
					(fill yes)
				)
			)
		)
		(pad "2" smd custom
			(at 0 0.2794 90)
			(size 0.0762 0.0762)
			(layers "B.Cu" "B.Mask" "B.Paste")
			(net "GND")
			(options
				(clearance outline)
				(anchor circle)
			)
			(primitives
				(gr_poly
					(pts
						(arc
							(start 0.1524 0.127)
							(mid 0.137521 0.162921)
							(end 0.1016 0.1778)
						)
						(arc
							(start -0.1016 0.1778)
							(mid -0.137521 0.162921)
							(end -0.1524 0.127)
						)
						(arc
							(start -0.1524 -0.127)
							(mid -0.137521 -0.162921)
							(end -0.1016 -0.1778)
						)
						(arc
							(start 0.1016 -0.1778)
							(mid 0.137521 -0.162921)
							(end 0.1524 -0.127)
						)
					)
					(width 0)
					(fill yes)
				)
			)
		)
	)
)
